# S9S_MB_2U (Grand Teton) — schematic netlist excerpt (pin names and nets, part order shuffled) for the footprints in the layout excerpt that follows; sources: Cadence DE-HDL packaged netlist, KiCad conversion of 03242023_DA0F0TMBIJ0_F0T_Motherboard_J_brd_V01_OCP.brd

R4397  Q_RES  1.5K 1% CHIP  pkg 0402LF  page 121 : A = H_CPU0_THERMTRIP_N ; B = H_CPU0_THERMTRIP_R_N
R1215  Q_RES  49.9 1% CHIP  pkg 0402LF  page 202 : A = IRQ_ESPI_LPC_SERIRQ_ALERT_N ; B = IRQ_ESPI_LPC_SERIRQ_ALERT_R_N

(kicad_pcb
	(version 20260206)
	(generator "pcbnew")
	(generator_version "10.0")
	(general
		(thickness 1.6)
		(legacy_teardrops no)
	)
	(paper "A4")
	(title_block
		(title "03242023_DA0F0TMBIJ0_F0T_Motherboard_J_brd_V01_OCP.brd")
		(comment 1 "Grand Teton / footprints 192-193 of 6105")
	)
	(layers
		(0 "F.Cu" signal "TOP")
		(4 "In1.Cu" signal "GND")
		(6 "In2.Cu" signal "IN1")
		(8 "In3.Cu" signal "GND1")
		(10 "In4.Cu" signal "IN2")
		(12 "In5.Cu" signal "GND2")
		(14 "In6.Cu" signal "IN3")
		(16 "In7.Cu" signal "GND3")
		(18 "In8.Cu" signal "VCC")
		(20 "In9.Cu" signal "VCC1")
		(22 "In10.Cu" signal "GND4")
		(24 "In11.Cu" signal "IN4")
		(26 "In12.Cu" signal "GND5")
		(28 "In13.Cu" signal "IN5")
		(30 "In14.Cu" signal "GND6")
		(32 "In15.Cu" signal "IN6")
		(34 "In16.Cu" signal "GND7")
		(2 "B.Cu" signal "BOTTOM")
		(9 "F.Adhes" user "F.Adhesive")
		(11 "B.Adhes" user "B.Adhesive")
		(13 "F.Paste" user "Package Geometry/Pastemask Top")
		(15 "B.Paste" user "Package Geometry/Pastemask Bottom")
		(5 "F.SilkS" user "Ref Des/Silkscreen Top")
		(7 "B.SilkS" user "Ref Des/Silkscreen Bottom")
		(1 "F.Mask" user "Board Geometry/Soldermask Top")
		(3 "B.Mask" user "Board Geometry/Soldermask Bottom")
		(17 "Dwgs.User" user "User.Drawings")
		(19 "Cmts.User" user "User.Comments")
		(21 "Eco1.User" user "User.Eco1")
		(23 "Eco2.User" user "User.Eco2")
		(25 "Edge.Cuts" user "Board Geometry/Outline")
		(27 "Margin" user)
		(31 "F.CrtYd" user "Package Geometry/Place Bound Top")
		(29 "B.CrtYd" user "Package Geometry/Place Bound Bottom")
		(35 "F.Fab" user "Ref Des/Assembly Top")
		(33 "B.Fab" user "Ref Des/Assembly Bottom")
	)
	(footprint ""
		(layer "F.Cu")
		(at 122.35688 -99.405948)
		(property "Reference" "R4397"
			(at 0 0 0)
			(layer "F.SilkS")
			(hide yes)
			(effects
				(font
					(size 1.27 1.27)
				)
			)
		)
		(property "Value" ""
			(at 0 0 0)
			(layer "F.Fab")
			(effects
				(font
					(size 1.27 1.27)
				)
			)
		)
		(duplicate_pad_numbers_are_jumpers no)
		(fp_line
			(start -0.7874 -0.4064)
			(end 0.7874 -0.4064)
			(stroke
				(width 0.1524)
				(type default)
			)
			(layer "F.SilkS")
		)
		(fp_line
			(start -0.7874 0.4064)
			(end -0.7874 -0.4064)
			(stroke
				(width 0.1524)
				(type default)
			)
			(layer "F.SilkS")
		)
		(fp_line
			(start 0.7874 -0.4064)
			(end 0.7874 0.4064)
			(stroke
				(width 0.1524)
				(type default)
			)
			(layer "F.SilkS")
		)
		(fp_line
			(start 0.7874 0.4064)
			(end -0.7874 0.4064)
			(stroke
				(width 0.1524)
				(type default)
			)
			(layer "F.SilkS")
		)
		(fp_line
			(start -0.67945 -0.305054)
			(end -0.12065 -0.305054)
			(stroke
				(width 0.1)
				(type default)
			)
			(layer "F.Fab")
		)
		(fp_line
			(start -0.67945 0.3048)
			(end -0.67945 -0.305054)
			(stroke
				(width 0.1)
				(type default)
			)
			(layer "F.Fab")
		)
		(fp_line
			(start -0.12065 -0.305054)
			(end -0.12065 -0.2794)
			(stroke
				(width 0.1)
				(type default)
			)
			(layer "F.Fab")
		)
		(fp_line
			(start -0.12065 -0.2794)
			(end 0.12065 -0.2794)
			(stroke
				(width 0.1)
				(type default)
			)
			(layer "F.Fab")
		)
		(fp_line
			(start -0.12065 0.2794)
			(end -0.12065 0.3048)
			(stroke
				(width 0.1)
				(type default)
			)
			(layer "F.Fab")
		)
		(fp_line
			(start -0.12065 0.3048)
			(end -0.67945 0.3048)
			(stroke
				(width 0.1)
				(type default)
			)
			(layer "F.Fab")
		)
		(fp_line
			(start 0.120396 0.2794)
			(end -0.12065 0.2794)
			(stroke
				(width 0.1)
				(type default)
			)
			(layer "F.Fab")
		)
		(fp_line
			(start 0.120396 0.3048)
			(end 0.120396 0.2794)
			(stroke
				(width 0.1)
				(type default)
			)
			(layer "F.Fab")
		)
		(fp_line
			(start 0.12065 -0.3048)
			(end 0.67945 -0.3048)
			(stroke
				(width 0.1)
				(type default)
			)
			(layer "F.Fab")
		)
		(fp_line
			(start 0.12065 -0.2794)
			(end 0.12065 -0.3048)
			(stroke
				(width 0.1)
				(type default)
			)
			(layer "F.Fab")
		)
		(fp_line
			(start 0.67945 -0.3048)
			(end 0.67945 0.3048)
			(stroke
				(width 0.1)
				(type default)
			)
			(layer "F.Fab")
		)
		(fp_line
			(start 0.67945 0.3048)
			(end 0.120396 0.3048)
			(stroke
				(width 0.1)
				(type default)
			)
			(layer "F.Fab")
		)
		(pad "1" smd circle
			(at -0.40005 0)
			(size 0 0)
			(layers "F.Cu" "F.Mask" "F.Paste")
			(net "H_CPU0_THERMTRIP_N")
		)
		(pad "2" smd circle
			(at 0.40005 0)
			(size 0 0)
			(layers "F.Cu" "F.Mask" "F.Paste")
			(net "H_CPU0_THERMTRIP_R_N")
		)
	)
	(footprint ""
		(layer "F.Cu")
		(at 335.754726 -16.200628 -90)
		(property "Reference" "R1215"
			(at 0 0 270)
			(layer "F.SilkS")
			(hide yes)
			(effects
				(font
					(size 1.27 1.27)
				)
			)
		)
		(property "Value" ""
			(at 0 0 270)
			(layer "F.Fab")
			(effects
				(font
					(size 1.27 1.27)
				)
			)
		)
		(duplicate_pad_numbers_are_jumpers no)
		(fp_line
			(start -0.7874 0.4064)
			(end -0.7874 -0.4064)
			(stroke
				(width 0.1524)
				(type default)
			)
			(layer "F.SilkS")
		)
		(fp_line
			(start 0.7874 0.4064)
			(end -0.7874 0.4064)
			(stroke
				(width 0.1524)
				(type default)
			)
			(layer "F.SilkS")
		)
		(fp_line
			(start -0.7874 -0.4064)
			(end 0.7874 -0.4064)
			(stroke
				(width 0.1524)
				(type default)
			)
			(layer "F.SilkS")
		)
		(fp_line
			(start 0.7874 -0.4064)
			(end 0.7874 0.4064)
			(stroke
				(width 0.1524)
				(type default)
			)
			(layer "F.SilkS")
		)
		(fp_line
			(start -0.67945 0.3048)
			(end -0.67945 -0.305054)
			(stroke
				(width 0.1)
				(type default)
			)
			(layer "F.Fab")
		)
		(fp_line
			(start -0.12065 0.3048)
			(end -0.67945 0.3048)
			(stroke
				(width 0.1)
				(type default)
			)
			(layer "F.Fab")
		)
		(fp_line
			(start 0.120396 0.3048)
			(end 0.120396 0.2794)
			(stroke
				(width 0.1)
				(type default)
			)
			(layer "F.Fab")
		)
		(fp_line
			(start 0.67945 0.3048)
			(end 0.120396 0.3048)
			(stroke
				(width 0.1)
				(type default)
			)
			(layer "F.Fab")
		)
		(fp_line
			(start -0.12065 0.2794)
			(end -0.12065 0.3048)
			(stroke
				(width 0.1)
				(type default)
			)
			(layer "F.Fab")
		)
		(fp_line
			(start 0.120396 0.2794)
			(end -0.12065 0.2794)
			(stroke
				(width 0.1)
				(type default)
			)
			(layer "F.Fab")
		)
		(fp_line
			(start -0.12065 -0.2794)
			(end 0.12065 -0.2794)
			(stroke
				(width 0.1)
				(type default)
			)
			(layer "F.Fab")
		)
		(fp_line
			(start 0.12065 -0.2794)
			(end 0.12065 -0.3048)
			(stroke
				(width 0.1)
				(type default)
			)
			(layer "F.Fab")
		)
		(fp_line
			(start 0.12065 -0.3048)
			(end 0.67945 -0.3048)
			(stroke
				(width 0.1)
				(type default)
			)
			(layer "F.Fab")
		)
		(fp_line
			(start 0.67945 -0.3048)
			(end 0.67945 0.3048)
			(stroke
				(width 0.1)
				(type default)
			)
			(layer "F.Fab")
		)
		(fp_line
			(start -0.67945 -0.305054)
			(end -0.12065 -0.305054)
			(stroke
				(width 0.1)
				(type default)
			)
			(layer "F.Fab")
		)
		(fp_line
			(start -0.12065 -0.305054)
			(end -0.12065 -0.2794)
			(stroke
				(width 0.1)
				(type default)
			)
			(layer "F.Fab")
		)
		(pad "1" smd circle
			(at -0.40005 0 270)
			(size 0 0)
			(layers "F.Cu" "F.Mask" "F.Paste")
			(net "IRQ_ESPI_LPC_SERIRQ_ALERT_N")
		)
		(pad "2" smd circle
			(at 0.40005 0 270)
			(size 0 0)
			(layers "F.Cu" "F.Mask" "F.Paste")
			(net "IRQ_ESPI_LPC_SERIRQ_ALERT_R_N")
		)
	)
)
